(kicad_pcb
	(version 20260206)
	(generator "pcbnew")
	(generator_version "10.0")
	(general
		(thickness 1.6)
		(legacy_teardrops no)
	)
	(paper "A4")
	(title_block
		(title "dpb — 14545-sa.0730WZS0815.brd")
		(comment 1 "Honey Badger (Wiwynn) / footprints 991-998 of 1066")
	)
	(layers
		(0 "F.Cu" signal "TOP")
		(4 "In1.Cu" signal "L2GND")
		(6 "In2.Cu" signal "L3")
		(8 "In3.Cu" signal "L4VCC")
		(10 "In4.Cu" signal "L5VCC")
		(12 "In5.Cu" signal "L6")
		(14 "In6.Cu" signal "L7GND")
		(2 "B.Cu" signal "BOTTOM")
		(9 "F.Adhes" user "F.Adhesive")
		(11 "B.Adhes" user "B.Adhesive")
		(13 "F.Paste" user "Package Geometry/Pastemask Top")
		(15 "B.Paste" user "Package Geometry/Pastemask Bottom")
		(5 "F.SilkS" user "Ref Des/Silkscreen Top")
		(7 "B.SilkS" user "Ref Des/Silkscreen Bottom")
		(1 "F.Mask" user "Board Geometry/Soldermask Top")
		(3 "B.Mask" user "Board Geometry/Soldermask Bottom")
		(17 "Dwgs.User" user "User.Drawings")
		(19 "Cmts.User" user "User.Comments")
		(21 "Eco1.User" user "User.Eco1")
		(23 "Eco2.User" user "User.Eco2")
		(25 "Edge.Cuts" user "Board Geometry/Outline")
		(27 "Margin" user)
		(31 "F.CrtYd" user "Package Geometry/Place Bound Top")
		(29 "B.CrtYd" user "Package Geometry/Place Bound Bottom")
		(35 "F.Fab" user "Ref Des/Assembly Top")
		(33 "B.Fab" user "Ref Des/Assembly Bottom")
	)
	(footprint ""
		(layer "F.Cu")
		(at 35.052 -307.34 90)
		(property "Reference" "R559"
			(at 0 0 90)
			(layer "F.SilkS")
			(hide yes)
			(effects
				(font
					(size 1.27 1.27)
				)
			)
		)
		(property "Value" "200KR2F-L-GP"
			(at 0.064008 -3.993896 90)
			(unlocked yes)
			(layer "F.Fab")
			(hide yes)
			(effects
				(font
					(size 1.016 1.016)
					(thickness 0.1524)
				)
			)
		)
		(property "Device Type" "R402H16"
			(at 0.064008 -5.517896 90)
			(unlocked yes)
			(layer "F.Fab")
			(hide yes)
			(effects
				(font
					(size 1.016 1.016)
					(thickness 0.1524)
				)
			)
		)
		(duplicate_pad_numbers_are_jumpers no)
		(fp_line
			(start 0.508 -0.9398)
			(end -0.508 -0.9398)
			(stroke
				(width 0.1524)
				(type default)
			)
			(layer "F.SilkS")
		)
		(fp_line
			(start -0.508 -0.9398)
			(end -0.508 0.9398)
			(stroke
				(width 0.1524)
				(type default)
			)
			(layer "F.SilkS")
		)
		(fp_rect
			(start -0.508 0.9398)
			(end 0.508 -0.9398)
			(stroke
				(width 0)
				(type default)
			)
			(fill no)
			(layer "F.CrtYd")
		)
		(fp_rect
			(start -0.508 0.9398)
			(end 0.508 -0.9398)
			(stroke
				(width 0)
				(type default)
			)
			(fill no)
			(layer "F.Fab")
		)
		(pad "1" smd custom
			(at 0 -0.4445 90)
			(size 0.1397 0.1397)
			(layers "F.Cu" "F.Mask" "F.Paste")
			(net "SW_HDD11_R")
			(options
				(clearance outline)
				(anchor circle)
			)
			(primitives
				(gr_poly
					(pts
						(arc
							(start -0.1778 -0.2794)
							(mid -0.249642 -0.249642)
							(end -0.2794 -0.1778)
						)
						(arc
							(start -0.2794 0.1778)
							(mid -0.249642 0.249642)
							(end -0.1778 0.2794)
						)
						(arc
							(start 0.1778 0.2794)
							(mid 0.249642 0.249642)
							(end 0.2794 0.1778)
						)
						(arc
							(start 0.2794 -0.1778)
							(mid 0.249642 -0.249642)
							(end 0.1778 -0.2794)
						)
					)
					(width 0)
					(fill yes)
				)
			)
		)
		(pad "2" smd custom
			(at 0 0.4445 90)
			(size 0.1397 0.1397)
			(layers "F.Cu" "F.Mask" "F.Paste")
			(net "SW_HDD11_N")
			(options
				(clearance outline)
				(anchor circle)
			)
			(primitives
				(gr_poly
					(pts
						(arc
							(start -0.1778 -0.2794)
							(mid -0.249642 -0.249642)
							(end -0.2794 -0.1778)
						)
						(arc
							(start -0.2794 0.1778)
							(mid -0.249642 0.249642)
							(end -0.1778 0.2794)
						)
						(arc
							(start 0.1778 0.2794)
							(mid 0.249642 0.249642)
							(end 0.2794 0.1778)
						)
						(arc
							(start 0.2794 -0.1778)
							(mid 0.249642 -0.249642)
							(end 0.1778 -0.2794)
						)
					)
					(width 0)
					(fill yes)
				)
			)
		)
	)
	(footprint ""
		(layer "F.Cu")
		(at 46.736 -107.315)
		(property "Reference" "C392"
			(at 0 0 0)
			(layer "F.SilkS")
			(hide yes)
			(effects
				(font
					(size 1.27 1.27)
				)
			)
		)
		(property "Value" "SCD033U25V2KX-GP"
			(at 1.1811 -2.7051 0)
			(unlocked yes)
			(layer "F.Fab")
			(hide yes)
			(effects
				(font
					(size 1.016 1.016)
					(thickness 0.1524)
				)
			)
		)
		(property "Device Type" "C402H22"
			(at 1.1811 -4.2291 0)
			(unlocked yes)
			(layer "F.Fab")
			(hide yes)
			(effects
				(font
					(size 1.016 1.016)
					(thickness 0.1524)
				)
			)
		)
		(duplicate_pad_numbers_are_jumpers no)
		(fp_rect
			(start -0.4318 0.9525)
			(end 0.4318 -0.9525)
			(stroke
				(width 0)
				(type default)
			)
			(fill no)
			(layer "F.CrtYd")
		)
		(fp_rect
			(start -0.4318 0.9525)
			(end 0.4318 -0.9525)
			(stroke
				(width 0)
				(type default)
			)
			(fill no)
			(layer "F.Fab")
		)
		(pad "1" smd custom
			(at 0 -0.4445)
			(size 0.1524 0.1524)
			(layers "F.Cu" "F.Mask" "F.Paste")
			(net "P12V")
			(options
				(clearance outline)
				(anchor circle)
			)
			(primitives
				(gr_poly
					(pts
						(arc
							(start 0.3048 -0.2032)
							(mid 0.275042 -0.275042)
							(end 0.2032 -0.3048)
						)
						(arc
							(start -0.2032 -0.3048)
							(mid -0.275042 -0.275042)
							(end -0.3048 -0.2032)
						)
						(arc
							(start -0.3048 0.2032)
							(mid -0.275042 0.275042)
							(end -0.2032 0.3048)
						)
						(arc
							(start 0.2032 0.3048)
							(mid 0.275042 0.275042)
							(end 0.3048 0.2032)
						)
					)
					(width 0)
					(fill yes)
				)
			)
		)
		(pad "2" smd custom
			(at 0 0.4445)
			(size 0.1524 0.1524)
			(layers "F.Cu" "F.Mask" "F.Paste")
			(net "SW_HDD13_N")
			(options
				(clearance outline)
				(anchor circle)
			)
			(primitives
				(gr_poly
					(pts
						(arc
							(start 0.3048 -0.2032)
							(mid 0.275042 -0.275042)
							(end 0.2032 -0.3048)
						)
						(arc
							(start -0.2032 -0.3048)
							(mid -0.275042 -0.275042)
							(end -0.3048 -0.2032)
						)
						(arc
							(start -0.3048 0.2032)
							(mid -0.275042 0.275042)
							(end -0.2032 0.3048)
						)
						(arc
							(start 0.2032 0.3048)
							(mid 0.275042 0.275042)
							(end 0.3048 0.2032)
						)
					)
					(width 0)
					(fill yes)
				)
			)
		)
	)
	(footprint ""
		(layer "F.Cu")
		(at 179.463446 -457.107036)
		(property "Reference" "R484"
			(at 0 0 0)
			(layer "F.SilkS")
			(hide yes)
			(effects
				(font
					(size 1.27 1.27)
				)
			)
		)
		(property "Value" "10KR2F-2-GP"
			(at 0.064008 -3.993896 0)
			(unlocked yes)
			(layer "F.Fab")
			(hide yes)
			(effects
				(font
					(size 1.016 1.016)
					(thickness 0.1524)
				)
			)
		)
		(property "Device Type" "R402H16"
			(at 0.064008 -5.517896 0)
			(unlocked yes)
			(layer "F.Fab")
			(hide yes)
			(effects
				(font
					(size 1.016 1.016)
					(thickness 0.1524)
				)
			)
		)
		(duplicate_pad_numbers_are_jumpers no)
		(fp_line
			(start -0.508 -0.9398)
			(end -0.508 0.9398)
			(stroke
				(width 0.1524)
				(type default)
			)
			(layer "F.SilkS")
		)
		(fp_line
			(start 0.508 -0.9398)
			(end -0.508 -0.9398)
			(stroke
				(width 0.1524)
				(type default)
			)
			(layer "F.SilkS")
		)
		(fp_rect
			(start -0.508 0.9398)
			(end 0.508 -0.9398)
			(stroke
				(width 0)
				(type default)
			)
			(fill no)
			(layer "F.CrtYd")
		)
		(fp_rect
			(start -0.508 0.9398)
			(end 0.508 -0.9398)
			(stroke
				(width 0)
				(type default)
			)
			(fill no)
			(layer "F.Fab")
		)
		(pad "1" smd custom
			(at 0 -0.4445)
			(size 0.1397 0.1397)
			(layers "F.Cu" "F.Mask" "F.Paste")
			(net "P5VC_DIV")
			(options
				(clearance outline)
				(anchor circle)
			)
			(primitives
				(gr_poly
					(pts
						(arc
							(start -0.1778 -0.2794)
							(mid -0.249642 -0.249642)
							(end -0.2794 -0.1778)
						)
						(arc
							(start -0.2794 0.1778)
							(mid -0.249642 0.249642)
							(end -0.1778 0.2794)
						)
						(arc
							(start 0.1778 0.2794)
							(mid 0.249642 0.249642)
							(end 0.2794 0.1778)
						)
						(arc
							(start 0.2794 -0.1778)
							(mid 0.249642 -0.249642)
							(end 0.1778 -0.2794)
						)
					)
					(width 0)
					(fill yes)
				)
			)
		)
		(pad "2" smd custom
			(at 0 0.4445)
			(size 0.1397 0.1397)
			(layers "F.Cu" "F.Mask" "F.Paste")
			(net "GND")
			(options
				(clearance outline)
				(anchor circle)
			)
			(primitives
				(gr_poly
					(pts
						(arc
							(start -0.1778 -0.2794)
							(mid -0.249642 -0.249642)
							(end -0.2794 -0.1778)
						)
						(arc
							(start -0.2794 0.1778)
							(mid -0.249642 0.249642)
							(end -0.1778 0.2794)
						)
						(arc
							(start 0.1778 0.2794)
							(mid 0.249642 0.249642)
							(end 0.2794 0.1778)
						)
						(arc
							(start 0.2794 -0.1778)
							(mid 0.249642 -0.249642)
							(end 0.1778 -0.2794)
						)
					)
					(width 0)
					(fill yes)
				)
			)
		)
	)
	(footprint ""
		(layer "F.Cu")
		(at 215.9508 -393.9032 180)
		(property "Reference" "C128"
			(at 0 0 180)
			(layer "F.SilkS")
			(hide yes)
			(effects
				(font
					(size 1.27 1.27)
				)
			)
		)
		(property "Value" "SC10U25V6KX-1GP"
			(at -0.0762 -5.1308 180)
			(unlocked yes)
			(layer "F.Fab")
			(hide yes)
			(effects
				(font
					(size 1.016 1.016)
					(thickness 0.1524)
				)
			)
		)
		(property "Device Type" "C1206H71"
			(at -0.127 -6.6548 180)
			(unlocked yes)
			(layer "F.Fab")
			(hide yes)
			(effects
				(font
					(size 1.016 1.016)
					(thickness 0.1524)
				)
			)
		)
		(duplicate_pad_numbers_are_jumpers no)
		(fp_line
			(start 1.016 2.2352)
			(end -1.016 2.2352)
			(stroke
				(width 0.1524)
				(type default)
			)
			(layer "F.SilkS")
		)
		(fp_line
			(start 1.016 0.8382)
			(end 1.016 2.2352)
			(stroke
				(width 0.1524)
				(type default)
			)
			(layer "F.SilkS")
		)
		(fp_line
			(start 1.016 -2.2352)
			(end 1.016 -0.8382)
			(stroke
				(width 0.1524)
				(type default)
			)
			(layer "F.SilkS")
		)
		(fp_line
			(start -1.016 2.2352)
			(end -1.016 0.8382)
			(stroke
				(width 0.1524)
				(type default)
			)
			(layer "F.SilkS")
		)
		(fp_line
			(start -1.016 -0.8382)
			(end -1.016 -2.2352)
			(stroke
				(width 0.1524)
				(type default)
			)
			(layer "F.SilkS")
		)
		(fp_line
			(start -1.016 -2.2352)
			(end 1.016 -2.2352)
			(stroke
				(width 0.1524)
				(type default)
			)
			(layer "F.SilkS")
		)
		(fp_rect
			(start -1.0922 2.3114)
			(end 1.0922 -2.3114)
			(stroke
				(width 0)
				(type default)
			)
			(fill no)
			(layer "F.CrtYd")
		)
		(fp_poly
			(pts
				(xy 1.0922 -2.3114) (xy 1.0922 2.3114) (xy -1.0922 2.3114) (xy -1.0922 -2.3114)
			)
			(stroke
				(width 0)
				(type default)
			)
			(fill no)
			(layer "F.Fab")
		)
		(pad "1" smd rect
			(at 0 -1.397 180)
			(size 1.651 1.27)
			(layers "F.Cu" "F.Mask" "F.Paste")
			(net "P12V_HDD1")
		)
		(pad "2" smd rect
			(at 0 1.397 180)
			(size 1.651 1.27)
			(layers "F.Cu" "F.Mask" "F.Paste")
			(net "GND")
		)
	)
	(footprint ""
		(layer "F.Cu")
		(at 52.323746 -228.603302)
		(property "Reference" "R468"
			(at 0 0 0)
			(layer "F.SilkS")
			(hide yes)
			(effects
				(font
					(size 1.27 1.27)
				)
			)
		)
		(property "Value" "4K7R2J-2-GP"
			(at 0.064008 -3.993896 0)
			(unlocked yes)
			(layer "F.Fab")
			(hide yes)
			(effects
				(font
					(size 1.016 1.016)
					(thickness 0.1524)
				)
			)
		)
		(property "Device Type" "R402H16"
			(at 0.064008 -5.517896 0)
			(unlocked yes)
			(layer "F.Fab")
			(hide yes)
			(effects
				(font
					(size 1.016 1.016)
					(thickness 0.1524)
				)
			)
		)
		(duplicate_pad_numbers_are_jumpers no)
		(fp_line
			(start -0.508 -0.9398)
			(end -0.508 0.9398)
			(stroke
				(width 0.1524)
				(type default)
			)
			(layer "F.SilkS")
		)
		(fp_line
			(start 0.508 -0.9398)
			(end -0.508 -0.9398)
			(stroke
				(width 0.1524)
				(type default)
			)
			(layer "F.SilkS")
		)
		(fp_rect
			(start -0.508 0.9398)
			(end 0.508 -0.9398)
			(stroke
				(width 0)
				(type default)
			)
			(fill no)
			(layer "F.CrtYd")
		)
		(fp_rect
			(start -0.508 0.9398)
			(end 0.508 -0.9398)
			(stroke
				(width 0)
				(type default)
			)
			(fill no)
			(layer "F.Fab")
		)
		(pad "1" smd custom
			(at 0 -0.4445)
			(size 0.1397 0.1397)
			(layers "F.Cu" "F.Mask" "F.Paste")
			(net "P3V3")
			(options
				(clearance outline)
				(anchor circle)
			)
			(primitives
				(gr_poly
					(pts
						(arc
							(start -0.1778 -0.2794)
							(mid -0.249642 -0.249642)
							(end -0.2794 -0.1778)
						)
						(arc
							(start -0.2794 0.1778)
							(mid -0.249642 0.249642)
							(end -0.1778 0.2794)
						)
						(arc
							(start 0.1778 0.2794)
							(mid 0.249642 0.249642)
							(end 0.2794 0.1778)
						)
						(arc
							(start 0.2794 -0.1778)
							(mid 0.249642 -0.249642)
							(end 0.1778 -0.2794)
						)
					)
					(width 0)
					(fill yes)
				)
			)
		)
		(pad "2" smd custom
			(at 0 0.4445)
			(size 0.1397 0.1397)
			(layers "F.Cu" "F.Mask" "F.Paste")
			(net "SAS2X28_A_HDD12_FLT")
			(options
				(clearance outline)
				(anchor circle)
			)
			(primitives
				(gr_poly
					(pts
						(arc
							(start -0.1778 -0.2794)
							(mid -0.249642 -0.249642)
							(end -0.2794 -0.1778)
						)
						(arc
							(start -0.2794 0.1778)
							(mid -0.249642 0.249642)
							(end -0.1778 0.2794)
						)
						(arc
							(start 0.1778 0.2794)
							(mid 0.249642 0.249642)
							(end 0.2794 0.1778)
						)
						(arc
							(start 0.2794 -0.1778)
							(mid 0.249642 -0.249642)
							(end 0.1778 -0.2794)
						)
					)
					(width 0)
					(fill yes)
				)
			)
		)
	)
	(footprint ""
		(layer "F.Cu")
		(at 191.389 -293.243 90)
		(property "Reference" "R136"
			(at 0 0 90)
			(layer "F.SilkS")
			(hide yes)
			(effects
				(font
					(size 1.27 1.27)
				)
			)
		)
		(property "Value" "4K7R2J-2-GP"
			(at 0.064008 -3.993896 90)
			(unlocked yes)
			(layer "F.Fab")
			(hide yes)
			(effects
				(font
					(size 1.016 1.016)
					(thickness 0.1524)
				)
			)
		)
		(property "Device Type" "R402H16"
			(at 0.064008 -5.517896 90)
			(unlocked yes)
			(layer "F.Fab")
			(hide yes)
			(effects
				(font
					(size 1.016 1.016)
					(thickness 0.1524)
				)
			)
		)
		(duplicate_pad_numbers_are_jumpers no)
		(fp_line
			(start 0.508 -0.9398)
			(end -0.508 -0.9398)
			(stroke
				(width 0.1524)
				(type default)
			)
			(layer "F.SilkS")
		)
		(fp_line
			(start -0.508 -0.9398)
			(end -0.508 0.9398)
			(stroke
				(width 0.1524)
				(type default)
			)
			(layer "F.SilkS")
		)
		(fp_rect
			(start -0.508 0.9398)
			(end 0.508 -0.9398)
			(stroke
				(width 0)
				(type default)
			)
			(fill no)
			(layer "F.CrtYd")
		)
		(fp_rect
			(start -0.508 0.9398)
			(end 0.508 -0.9398)
			(stroke
				(width 0)
				(type default)
			)
			(fill no)
			(layer "F.Fab")
		)
		(pad "1" smd custom
			(at 0 -0.4445 90)
			(size 0.1397 0.1397)
			(layers "F.Cu" "F.Mask" "F.Paste")
			(net "P12V")
			(options
				(clearance outline)
				(anchor circle)
			)
			(primitives
				(gr_poly
					(pts
						(arc
							(start -0.1778 -0.2794)
							(mid -0.249642 -0.249642)
							(end -0.2794 -0.1778)
						)
						(arc
							(start -0.2794 0.1778)
							(mid -0.249642 0.249642)
							(end -0.1778 0.2794)
						)
						(arc
							(start 0.1778 0.2794)
							(mid 0.249642 0.249642)
							(end 0.2794 0.1778)
						)
						(arc
							(start 0.2794 -0.1778)
							(mid 0.249642 -0.249642)
							(end 0.1778 -0.2794)
						)
					)
					(width 0)
					(fill yes)
				)
			)
		)
		(pad "2" smd custom
			(at 0 0.4445 90)
			(size 0.1397 0.1397)
			(layers "F.Cu" "F.Mask" "F.Paste")
			(net "SW_HDD2_R")
			(options
				(clearance outline)
				(anchor circle)
			)
			(primitives
				(gr_poly
					(pts
						(arc
							(start -0.1778 -0.2794)
							(mid -0.249642 -0.249642)
							(end -0.2794 -0.1778)
						)
						(arc
							(start -0.2794 0.1778)
							(mid -0.249642 0.249642)
							(end -0.1778 0.2794)
						)
						(arc
							(start 0.1778 0.2794)
							(mid 0.249642 0.249642)
							(end 0.2794 0.1778)
						)
						(arc
							(start 0.2794 -0.1778)
							(mid 0.249642 -0.249642)
							(end 0.1778 -0.2794)
						)
					)
					(width 0)
					(fill yes)
				)
			)
		)
	)
	(footprint ""
		(layer "F.Cu")
		(at 56.260746 -175.3997)
		(property "Reference" "R219"
			(at 0 0 0)
			(layer "F.SilkS")
			(hide yes)
			(effects
				(font
					(size 1.27 1.27)
				)
			)
		)
		(property "Value" "220R3F-1-GP"
			(at -0.0254 -2.5146 0)
			(unlocked yes)
			(layer "F.Fab")
			(hide yes)
			(effects
				(font
					(size 1.016 1.016)
					(thickness 0.1524)
				)
			)
		)
		(property "Device Type" "R603H22"
			(at -0.0254 -4.0386 0)
			(unlocked yes)
			(layer "F.Fab")
			(hide yes)
			(effects
				(font
					(size 1.016 1.016)
					(thickness 0.1524)
				)
			)
		)
		(duplicate_pad_numbers_are_jumpers no)
		(fp_line
			(start -0.4826 0)
			(end -0.2032 0)
			(stroke
				(width 0.2032)
				(type default)
			)
			(layer "F.SilkS")
		)
		(fp_line
			(start 0.2032 0)
			(end 0.4826 0)
			(stroke
				(width 0.2032)
				(type default)
			)
			(layer "F.SilkS")
		)
		(fp_rect
			(start -0.5842 1.3335)
			(end 0.5842 -1.3335)
			(stroke
				(width 0)
				(type default)
			)
			(fill no)
			(layer "F.CrtYd")
		)
		(fp_rect
			(start -0.5842 1.3335)
			(end 0.5842 -1.3335)
			(stroke
				(width 0)
				(type default)
			)
			(fill no)
			(layer "F.Fab")
		)
		(pad "1" smd custom
			(at 0 -0.762)
			(size 0.2159 0.2159)
			(layers "F.Cu" "F.Mask" "F.Paste")
			(net "HDD_PRSNT_NET8")
			(options
				(clearance outline)
				(anchor circle)
			)
			(primitives
				(gr_poly
					(pts
						(arc
							(start -0.3302 -0.4318)
							(mid -0.402042 -0.402042)
							(end -0.4318 -0.3302)
						)
						(arc
							(start -0.4318 0.3302)
							(mid -0.402042 0.402042)
							(end -0.3302 0.4318)
						)
						(arc
							(start 0.3302 0.4318)
							(mid 0.402042 0.402042)
							(end 0.4318 0.3302)
						)
						(arc
							(start 0.4318 -0.3302)
							(mid 0.402042 -0.402042)
							(end 0.3302 -0.4318)
						)
					)
					(width 0)
					(fill yes)
				)
			)
		)
		(pad "2" smd custom
			(at 0 0.762)
			(size 0.2159 0.2159)
			(layers "F.Cu" "F.Mask" "F.Paste")
			(net "HDD_PRSNT8")
			(options
				(clearance outline)
				(anchor circle)
			)
			(primitives
				(gr_poly
					(pts
						(arc
							(start -0.3302 -0.4318)
							(mid -0.402042 -0.402042)
							(end -0.4318 -0.3302)
						)
						(arc
							(start -0.4318 0.3302)
							(mid -0.402042 0.402042)
							(end -0.3302 0.4318)
						)
						(arc
							(start 0.3302 0.4318)
							(mid 0.402042 0.402042)
							(end 0.4318 0.3302)
						)
						(arc
							(start 0.4318 -0.3302)
							(mid 0.402042 -0.402042)
							(end 0.3302 -0.4318)
						)
					)
					(width 0)
					(fill yes)
				)
			)
		)
	)
	(footprint ""
		(layer "F.Cu")
		(at 59.943746 -8.5217 90)
		(property "Reference" "PC18"
			(at 0 0 90)
			(layer "F.SilkS")
			(hide yes)
			(effects
				(font
					(size 1.27 1.27)
				)
			)
		)
		(property "Value" "SC22U25V5MX-GP"
			(at -0.0762 -6.1214 90)
			(unlocked yes)
			(layer "F.Fab")
			(hide yes)
			(effects
				(font
					(size 1.016 1.016)
					(thickness 0.1524)
				)
			)
		)
		(property "Device Type" "C805H58"
			(at -0.0762 -8.1534 90)
			(unlocked yes)
			(layer "F.Fab")
			(hide yes)
			(effects
				(font
					(size 1.016 1.016)
					(thickness 0.1524)
				)
			)
		)
		(duplicate_pad_numbers_are_jumpers no)
		(fp_line
			(start 0.635 0)
			(end -0.635 0)
			(stroke
				(width 0.508)
				(type default)
			)
			(layer "F.SilkS")
		)
		(fp_rect
			(start -0.9652 1.778)
			(end 0.9652 -1.778)
			(stroke
				(width 0)
				(type default)
			)
			(fill no)
			(layer "F.CrtYd")
		)
		(fp_poly
			(pts
				(xy -0.9652 -1.778) (xy 0.9652 -1.778) (xy 0.9652 1.778) (xy -0.9652 1.778)
			)
			(stroke
				(width 0)
				(type default)
			)
			(fill no)
			(layer "F.Fab")
		)
		(pad "1" smd rect
			(at 0 -0.9652 90)
			(size 1.397 1.143)
			(layers "F.Cu" "F.Mask" "F.Paste")
			(net "P5VB_12VIN")
		)
		(pad "2" smd rect
			(at 0 0.9652 90)
			(size 1.397 1.143)
			(layers "F.Cu" "F.Mask" "F.Paste")
			(net "GND")
		)
	)
)
